(kicad_pcb
	(version 20241229)
	(generator "pcbnew")
	(generator_version "9.0")
	(general
		(thickness 1.711)
		(legacy_teardrops no)
	)
	(paper "A4")
	(title_block
		(title "Antmicro Baseboard for Jetson AGX Thor")
		(date "2026-02-18")
		(rev "1.1.0")
		(company "Antmicro Ltd")
		(comment 1 "www.antmicro.com")
		(comment 9 "footprints 1000-1004 of 1170")
	)
	(layers
		(0 "F.Cu" signal)
		(4 "In1.Cu" signal)
		(6 "In2.Cu" signal)
		(8 "In3.Cu" signal)
		(10 "In4.Cu" jumper)
		(12 "In5.Cu" signal)
		(14 "In6.Cu" signal)
		(16 "In7.Cu" signal)
		(18 "In8.Cu" signal)
		(2 "B.Cu" signal)
		(9 "F.Adhes" user "F.Adhesive")
		(11 "B.Adhes" user "B.Adhesive")
		(13 "F.Paste" user)
		(15 "B.Paste" user)
		(5 "F.SilkS" user "F.Silkscreen")
		(7 "B.SilkS" user "B.Silkscreen")
		(1 "F.Mask" user)
		(3 "B.Mask" user)
		(17 "Dwgs.User" user "User.Drawings")
		(19 "Cmts.User" user "User.Comments")
		(21 "Eco1.User" user "User.Eco1")
		(23 "Eco2.User" user "User.Eco2")
		(25 "Edge.Cuts" user)
		(27 "Margin" user)
		(31 "F.CrtYd" user "F.Courtyard")
		(29 "B.CrtYd" user "B.Courtyard")
		(35 "F.Fab" user)
		(33 "B.Fab" user)
	)
	(footprint "antmicro-footprints:R_0402_1005Metric"
		(layer "B.Cu")
		(at 207 63.453001)
		(descr "Resistor SMD 0402")
		(tags "resistor SMD 0402")
		(property "Reference" "R175"
			(at -3.77 -0.48 0)
			(layer "B.SilkS")
			(effects
				(font
					(size 0.7 0.7)
					(thickness 0.15)
				)
				(justify right top mirror)
			)
		)
		(property "Value" "R_100k_0402"
			(at -1.011843 -1.772046 0)
			(layer "B.Fab")
			(effects
				(font
					(size 0.7 0.7)
					(thickness 0.15)
				)
				(justify right top mirror)
			)
		)
		(property "Datasheet" "https://www.bourns.com/docs/product-datasheets/cr.pdf"
			(at 0 0 0)
			(layer "B.Fab")
			(hide yes)
			(effects
				(font
					(size 1.27 1.27)
					(thickness 0.15)
				)
				(justify mirror)
			)
		)
		(property "Description" "SMD Chip Resistor, 100 kohm, ± 1%, 62.5 mW, 0402 [1005 Metric], Thick Film, General Purpose"
			(at 0 0 0)
			(layer "B.Fab")
			(hide yes)
			(effects
				(font
					(size 1.27 1.27)
					(thickness 0.15)
				)
				(justify mirror)
			)
		)
		(property "Manufacturer" "Bourns"
			(at 0 0 180)
			(unlocked yes)
			(layer "B.Fab")
			(hide yes)
			(effects
				(font
					(size 1 1)
					(thickness 0.15)
				)
				(justify mirror)
			)
		)
		(property "MPN" "CR0402-FX-1003GLF"
			(at 0 0 180)
			(unlocked yes)
			(layer "B.Fab")
			(hide yes)
			(effects
				(font
					(size 1 1)
					(thickness 0.15)
				)
				(justify mirror)
			)
		)
		(property "Val" "100k"
			(at 0 0 180)
			(unlocked yes)
			(layer "B.Fab")
			(hide yes)
			(effects
				(font
					(size 1 1)
					(thickness 0.15)
				)
				(justify mirror)
			)
		)
		(property "License" "Apache-2.0"
			(at 0 0 180)
			(unlocked yes)
			(layer "B.Fab")
			(hide yes)
			(effects
				(font
					(size 1 1)
					(thickness 0.15)
				)
				(justify mirror)
			)
		)
		(property "Author" "Antmicro"
			(at 0 0 180)
			(unlocked yes)
			(layer "B.Fab")
			(hide yes)
			(effects
				(font
					(size 1 1)
					(thickness 0.15)
				)
				(justify mirror)
			)
		)
		(property "Tolerance" "1%"
			(at 0 0 180)
			(unlocked yes)
			(layer "B.Fab")
			(hide yes)
			(effects
				(font
					(size 1 1)
					(thickness 0.15)
				)
				(justify mirror)
			)
		)
		(sheetname "/CSI/")
		(sheetfile "csi.kicad_sch")
		(attr smd)
		(fp_poly
			(pts
				(xy -0.925 0.47) (xy -0.925 -0.47) (xy 0.925 -0.47) (xy 0.925 0.47)
			)
			(stroke
				(width 0.05)
				(type default)
			)
			(fill no)
			(layer "B.CrtYd")
		)
		(fp_poly
			(pts
				(xy -0.5 0.25) (xy -0.5 -0.25) (xy 0.5 -0.25) (xy 0.5 0.25)
			)
			(stroke
				(width 0.15)
				(type solid)
			)
			(fill no)
			(layer "B.Fab")
		)
		(fp_text user "License: Apache-2.0"
			(at -0.949999 -5.169 0)
			(layer "B.Fab")
			(effects
				(font
					(size 0.7 0.7)
					(thickness 0.15)
				)
				(justify right top mirror)
			)
		)
		(fp_text user "${REFERENCE}"
			(at -0.95 -3.168 0)
			(layer "B.Fab")
			(effects
				(font
					(size 0.7 0.7)
					(thickness 0.15)
				)
				(justify right top mirror)
			)
		)
		(fp_text user "Author: Antmicro"
			(at -0.95 -4.169 0)
			(layer "B.Fab")
			(effects
				(font
					(size 0.7 0.7)
					(thickness 0.15)
				)
				(justify right top mirror)
			)
		)
		(pad "1" smd roundrect
			(at -0.48 0)
			(size 0.59 0.64)
			(layers "B.Cu" "B.Mask" "B.Paste")
			(roundrect_rratio 0.25)
			(net 1 "GND")
			(pintype "passive")
		)
		(pad "2" smd roundrect
			(at 0.48 0)
			(size 0.59 0.64)
			(layers "B.Cu" "B.Mask" "B.Paste")
			(roundrect_rratio 0.25)
			(net 123 "/CSI/CAM_CTRL.CSIB_PEN")
			(pintype "passive")
		)
	)
	(footprint "antmicro-footprints:C_0402_1005Metric"
		(layer "B.Cu")
		(at 199.41 64.82)
		(descr "Capacitor SMD 0402")
		(tags "capacitor SMD 0402")
		(property "Reference" "C167"
			(at -1.41 -1.362 0)
			(layer "B.SilkS")
			(effects
				(font
					(size 0.7 0.7)
					(thickness 0.15)
				)
				(justify right top mirror)
			)
		)
		(property "Value" "C_100n_0402"
			(at -1.022927 -2.155213 0)
			(layer "B.Fab")
			(effects
				(font
					(size 0.7 0.7)
					(thickness 0.15)
				)
				(justify right top mirror)
			)
		)
		(property "Datasheet" "https://www.murata.com/products/productdetail?partno=GRM155R61H104KE14%23"
			(at 0 0 0)
			(layer "B.Fab")
			(hide yes)
			(effects
				(font
					(size 1.27 1.27)
					(thickness 0.15)
				)
				(justify mirror)
			)
		)
		(property "Description" "SMD Multilayer Ceramic Capacitor, 0.1 µF, 50 V, 0402 [1005 Metric], ± 10%, X5R, GRM Series"
			(at 0 0 0)
			(layer "B.Fab")
			(hide yes)
			(effects
				(font
					(size 1.27 1.27)
					(thickness 0.15)
				)
				(justify mirror)
			)
		)
		(property "Manufacturer" "Murata"
			(at 0 0 180)
			(unlocked yes)
			(layer "B.Fab")
			(hide yes)
			(effects
				(font
					(size 1 1)
					(thickness 0.15)
				)
				(justify mirror)
			)
		)
		(property "MPN" "GRM155R61H104KE14D"
			(at 0 0 180)
			(unlocked yes)
			(layer "B.Fab")
			(hide yes)
			(effects
				(font
					(size 1 1)
					(thickness 0.15)
				)
				(justify mirror)
			)
		)
		(property "Val" "100n"
			(at 0 0 180)
			(unlocked yes)
			(layer "B.Fab")
			(hide yes)
			(effects
				(font
					(size 1 1)
					(thickness 0.15)
				)
				(justify mirror)
			)
		)
		(property "License" "Apache-2.0"
			(at 0 0 180)
			(unlocked yes)
			(layer "B.Fab")
			(hide yes)
			(effects
				(font
					(size 1 1)
					(thickness 0.15)
				)
				(justify mirror)
			)
		)
		(property "Author" "Antmicro"
			(at 0 0 180)
			(unlocked yes)
			(layer "B.Fab")
			(hide yes)
			(effects
				(font
					(size 1 1)
					(thickness 0.15)
				)
				(justify mirror)
			)
		)
		(property "Voltage" "50V"
			(at 0 0 180)
			(unlocked yes)
			(layer "B.Fab")
			(hide yes)
			(effects
				(font
					(size 1 1)
					(thickness 0.15)
				)
				(justify mirror)
			)
		)
		(property "Dielectric" "X5R"
			(at 0 0 180)
			(unlocked yes)
			(layer "B.Fab")
			(hide yes)
			(effects
				(font
					(size 1 1)
					(thickness 0.15)
				)
				(justify mirror)
			)
		)
		(sheetname "/CSI/")
		(sheetfile "csi.kicad_sch")
		(attr smd)
		(fp_poly
			(pts
				(xy -0.925 0.47) (xy -0.925 -0.47) (xy 0.925 -0.47) (xy 0.925 0.47)
			)
			(stroke
				(width 0.05)
				(type default)
			)
			(fill no)
			(layer "B.CrtYd")
		)
		(fp_line
			(start -0.494 -0.248)
			(end -0.494 0.25)
			(stroke
				(width 0.15)
				(type solid)
			)
			(layer "B.Fab")
		)
		(fp_line
			(start -0.494 0.25)
			(end 0.504 0.25)
			(stroke
				(width 0.15)
				(type solid)
			)
			(layer "B.Fab")
		)
		(fp_line
			(start 0.504 -0.248)
			(end -0.494 -0.248)
			(stroke
				(width 0.15)
				(type solid)
			)
			(layer "B.Fab")
		)
		(fp_line
			(start 0.504 0.25)
			(end 0.504 -0.248)
			(stroke
				(width 0.15)
				(type solid)
			)
			(layer "B.Fab")
		)
		(fp_text user "Author: Antmicro"
			(at -0.939 -3.399 0)
			(layer "B.Fab")
			(effects
				(font
					(size 0.7 0.7)
					(thickness 0.15)
				)
				(justify right top mirror)
			)
		)
		(fp_text user "${REFERENCE}"
			(at -0.939 -4.599 0)
			(layer "B.Fab")
			(effects
				(font
					(size 0.7 0.7)
					(thickness 0.15)
				)
				(justify right top mirror)
			)
		)
		(fp_text user "License: Apache-2.0"
			(at -0.939 -5.799 0)
			(layer "B.Fab")
			(effects
				(font
					(size 0.7 0.7)
					(thickness 0.15)
				)
				(justify right top mirror)
			)
		)
		(pad "1" smd roundrect
			(at -0.48 0)
			(size 0.59 0.64)
			(layers "B.Cu" "B.Mask" "B.Paste")
			(roundrect_rratio 0.25)
			(net 1 "GND")
			(pintype "passive")
		)
		(pad "2" smd roundrect
			(at 0.48 0)
			(size 0.59 0.64)
			(layers "B.Cu" "B.Mask" "B.Paste")
			(roundrect_rratio 0.25)
			(net 2 "+3V3")
			(pintype "passive")
		)
	)
	(footprint "antmicro-footprints:C_0402_1005Metric"
		(layer "B.Cu")
		(at 180.23 93.1)
		(descr "Capacitor SMD 0402")
		(tags "capacitor SMD 0402")
		(property "Reference" "C261"
			(at -1.03 0.6 0)
			(layer "B.SilkS")
			(effects
				(font
					(size 0.7 0.7)
					(thickness 0.15)
				)
				(justify right top mirror)
			)
		)
		(property "Value" "C_1u_25V_0402"
			(at -1.022927 -2.155213 0)
			(layer "B.Fab")
			(effects
				(font
					(size 0.7 0.7)
					(thickness 0.15)
				)
				(justify right top mirror)
			)
		)
		(property "Datasheet" "https://www.murata.com/products/productdetail?partno=GRM155R61E105KE11%23"
			(at 0 0 0)
			(layer "B.Fab")
			(hide yes)
			(effects
				(font
					(size 1.27 1.27)
					(thickness 0.15)
				)
				(justify mirror)
			)
		)
		(property "Description" "SMD Multilayer Ceramic Capacitor, 1 µF, 25 V, 0402 [1005 Metric], ± 10%, X5R, GRM Series"
			(at 0 0 0)
			(layer "B.Fab")
			(hide yes)
			(effects
				(font
					(size 1.27 1.27)
					(thickness 0.15)
				)
				(justify mirror)
			)
		)
		(property "MPN" "GRM155R61E105KE11J"
			(at 0 0 180)
			(unlocked yes)
			(layer "B.Fab")
			(hide yes)
			(effects
				(font
					(size 1 1)
					(thickness 0.15)
				)
				(justify mirror)
			)
		)
		(property "Manufacturer" "Murata"
			(at 0 0 180)
			(unlocked yes)
			(layer "B.Fab")
			(hide yes)
			(effects
				(font
					(size 1 1)
					(thickness 0.15)
				)
				(justify mirror)
			)
		)
		(property "License" "Apache-2.0"
			(at 0 0 180)
			(unlocked yes)
			(layer "B.Fab")
			(hide yes)
			(effects
				(font
					(size 1 1)
					(thickness 0.15)
				)
				(justify mirror)
			)
		)
		(property "Author" "Antmicro"
			(at 0 0 180)
			(unlocked yes)
			(layer "B.Fab")
			(hide yes)
			(effects
				(font
					(size 1 1)
					(thickness 0.15)
				)
				(justify mirror)
			)
		)
		(property "Val" "1u"
			(at 0 0 180)
			(unlocked yes)
			(layer "B.Fab")
			(hide yes)
			(effects
				(font
					(size 1 1)
					(thickness 0.15)
				)
				(justify mirror)
			)
		)
		(property "Voltage" "25V"
			(at 0 0 180)
			(unlocked yes)
			(layer "B.Fab")
			(hide yes)
			(effects
				(font
					(size 1 1)
					(thickness 0.15)
				)
				(justify mirror)
			)
		)
		(property "Dielectric" "X5R"
			(at 0 0 180)
			(unlocked yes)
			(layer "B.Fab")
			(hide yes)
			(effects
				(font
					(size 1 1)
					(thickness 0.15)
				)
				(justify mirror)
			)
		)
		(sheetname "/Power/")
		(sheetfile "power.kicad_sch")
		(attr smd exclude_from_pos_files exclude_from_bom dnp)
		(fp_rect
			(start -0.925 0.47)
			(end 0.925 -0.47)
			(stroke
				(width 0.05)
				(type default)
			)
			(fill no)
			(layer "B.CrtYd")
		)
		(fp_line
			(start -0.494 -0.248)
			(end -0.494 0.25)
			(stroke
				(width 0.15)
				(type solid)
			)
			(layer "B.Fab")
		)
		(fp_line
			(start -0.494 0.25)
			(end 0.504 0.25)
			(stroke
				(width 0.15)
				(type solid)
			)
			(layer "B.Fab")
		)
		(fp_line
			(start 0.504 -0.248)
			(end -0.494 -0.248)
			(stroke
				(width 0.15)
				(type solid)
			)
			(layer "B.Fab")
		)
		(fp_line
			(start 0.504 0.25)
			(end 0.504 -0.248)
			(stroke
				(width 0.15)
				(type solid)
			)
			(layer "B.Fab")
		)
		(fp_text user "${REFERENCE}"
			(at -0.939 -4.599 0)
			(layer "B.Fab")
			(effects
				(font
					(size 0.7 0.7)
					(thickness 0.15)
				)
				(justify right top mirror)
			)
		)
		(fp_text user "Author: Antmicro"
			(at -0.939 -3.399 0)
			(layer "B.Fab")
			(effects
				(font
					(size 0.7 0.7)
					(thickness 0.15)
				)
				(justify right top mirror)
			)
		)
		(fp_text user "License: Apache-2.0"
			(at -0.939 -5.799 0)
			(layer "B.Fab")
			(effects
				(font
					(size 0.7 0.7)
					(thickness 0.15)
				)
				(justify right top mirror)
			)
		)
		(pad "1" smd roundrect
			(at -0.48 0)
			(size 0.59 0.64)
			(layers "B.Cu" "B.Mask" "B.Paste")
			(roundrect_rratio 0.25)
			(net 1 "GND")
			(pintype "passive")
		)
		(pad "2" smd roundrect
			(at 0.48 0)
			(size 0.59 0.64)
			(layers "B.Cu" "B.Mask" "B.Paste")
			(roundrect_rratio 0.25)
			(net 13 "VCC")
			(pintype "passive")
		)
	)
	(footprint "antmicro-footprints:R_0402_1005Metric"
		(layer "B.Cu")
		(at 205.395 104.79 180)
		(descr "Resistor SMD 0402")
		(tags "resistor SMD 0402")
		(property "Reference" "R280"
			(at -6.505 -0.46 0)
			(layer "B.SilkS")
			(effects
				(font
					(size 0.7 0.7)
					(thickness 0.15)
				)
				(justify left bottom mirror)
			)
		)
		(property "Value" "R_200k_0402"
			(at -1.011843 -1.772046 0)
			(layer "B.Fab")
			(effects
				(font
					(size 0.7 0.7)
					(thickness 0.15)
				)
				(justify left bottom mirror)
			)
		)
		(property "Datasheet" "https://www.bourns.com/docs/product-datasheets/cr.pdf"
			(at 0 0 0)
			(layer "B.Fab")
			(hide yes)
			(effects
				(font
					(size 1.27 1.27)
					(thickness 0.15)
				)
				(justify mirror)
			)
		)
		(property "Description" "SMD Chip Resistor, 200 kohm, ± 1%, 62.5 mW, 0402 [1005 Metric], Thick Film, General Purpose"
			(at 0 0 0)
			(layer "B.Fab")
			(hide yes)
			(effects
				(font
					(size 1.27 1.27)
					(thickness 0.15)
				)
				(justify mirror)
			)
		)
		(property "Manufacturer" "Bourns"
			(at 0 0 0)
			(unlocked yes)
			(layer "B.Fab")
			(hide yes)
			(effects
				(font
					(size 1 1)
					(thickness 0.15)
				)
				(justify mirror)
			)
		)
		(property "MPN" "CR0402-FX-2003GLF"
			(at 0 0 0)
			(unlocked yes)
			(layer "B.Fab")
			(hide yes)
			(effects
				(font
					(size 1 1)
					(thickness 0.15)
				)
				(justify mirror)
			)
		)
		(property "Val" "200k"
			(at 0 0 0)
			(unlocked yes)
			(layer "B.Fab")
			(hide yes)
			(effects
				(font
					(size 1 1)
					(thickness 0.15)
				)
				(justify mirror)
			)
		)
		(property "License" "Apache-2.0"
			(at 0 0 0)
			(unlocked yes)
			(layer "B.Fab")
			(hide yes)
			(effects
				(font
					(size 1 1)
					(thickness 0.15)
				)
				(justify mirror)
			)
		)
		(property "Author" "Antmicro"
			(at 0 0 0)
			(unlocked yes)
			(layer "B.Fab")
			(hide yes)
			(effects
				(font
					(size 1 1)
					(thickness 0.15)
				)
				(justify mirror)
			)
		)
		(property "Tolerance" "1%"
			(at 0 0 0)
			(unlocked yes)
			(layer "B.Fab")
			(hide yes)
			(effects
				(font
					(size 1 1)
					(thickness 0.15)
				)
				(justify mirror)
			)
		)
		(sheetname "/Recovery USB/")
		(sheetfile "recovery_usb.kicad_sch")
		(attr smd)
		(fp_poly
			(pts
				(xy -0.925 0.47) (xy -0.925 -0.47) (xy 0.925 -0.47) (xy 0.925 0.47)
			)
			(stroke
				(width 0.05)
				(type default)
			)
			(fill no)
			(layer "B.CrtYd")
		)
		(fp_poly
			(pts
				(xy -0.5 0.25) (xy -0.5 -0.25) (xy 0.5 -0.25) (xy 0.5 0.25)
			)
			(stroke
				(width 0.15)
				(type solid)
			)
			(fill no)
			(layer "B.Fab")
		)
		(fp_text user "License: Apache-2.0"
			(at -0.949999 -5.169 0)
			(layer "B.Fab")
			(effects
				(font
					(size 0.7 0.7)
					(thickness 0.15)
				)
				(justify left bottom mirror)
			)
		)
		(fp_text user "${REFERENCE}"
			(at -0.95 -3.168 0)
			(layer "B.Fab")
			(effects
				(font
					(size 0.7 0.7)
					(thickness 0.15)
				)
				(justify left bottom mirror)
			)
		)
		(fp_text user "Author: Antmicro"
			(at -0.95 -4.169 0)
			(layer "B.Fab")
			(effects
				(font
					(size 0.7 0.7)
					(thickness 0.15)
				)
				(justify left bottom mirror)
			)
		)
		(pad "1" smd roundrect
			(at -0.48 0 180)
			(size 0.59 0.64)
			(layers "B.Cu" "B.Mask" "B.Paste")
			(roundrect_rratio 0.25)
			(net 2 "+3V3")
			(pintype "passive")
		)
		(pad "2" smd roundrect
			(at 0.48 0 180)
			(size 0.59 0.64)
			(layers "B.Cu" "B.Mask" "B.Paste")
			(roundrect_rratio 0.25)
			(net 1025 "/Recovery USB/USBC2_I2C_SCL")
			(pintype "passive")
		)
	)
	(footprint "antmicro-footprints:R_0402_1005Metric"
		(layer "B.Cu")
		(at 203.4 105.800001)
		(descr "Resistor SMD 0402")
		(tags "resistor SMD 0402")
		(property "Reference" "R281"
			(at 2.9 -0.400001 0)
			(layer "B.SilkS")
			(effects
				(font
					(size 0.7 0.7)
					(thickness 0.15)
				)
				(justify right top mirror)
			)
		)
		(property "Value" "R_0R_0402"
			(at -1.011843 -1.772046 0)
			(layer "B.Fab")
			(effects
				(font
					(size 0.7 0.7)
					(thickness 0.15)
				)
				(justify right top mirror)
			)
		)
		(property "Datasheet" "https://industrial.panasonic.com/cdbs/www-data/pdf/RDA0000/AOA0000C301.pdf"
			(at 0 0 0)
			(layer "B.Fab")
			(hide yes)
			(effects
				(font
					(size 1.27 1.27)
					(thickness 0.15)
				)
				(justify mirror)
			)
		)
		(property "Description" "SMD Chip Resistor, Jumper, 0 ohm, 100 mW, 0402 [1005 Metric], Thick Film, General Purpose"
			(at 0 0 0)
			(layer "B.Fab")
			(hide yes)
			(effects
				(font
					(size 1.27 1.27)
					(thickness 0.15)
				)
				(justify mirror)
			)
		)
		(property "Manufacturer" "Panasonic"
			(at 0 0 180)
			(unlocked yes)
			(layer "B.Fab")
			(hide yes)
			(effects
				(font
					(size 1 1)
					(thickness 0.15)
				)
				(justify mirror)
			)
		)
		(property "MPN" "ERJ2GE0R00X"
			(at 0 0 180)
			(unlocked yes)
			(layer "B.Fab")
			(hide yes)
			(effects
				(font
					(size 1 1)
					(thickness 0.15)
				)
				(justify mirror)
			)
		)
		(property "Val" "0R"
			(at 0 0 180)
			(unlocked yes)
			(layer "B.Fab")
			(hide yes)
			(effects
				(font
					(size 1 1)
					(thickness 0.15)
				)
				(justify mirror)
			)
		)
		(property "License" "Apache-2.0"
			(at 0 0 180)
			(unlocked yes)
			(layer "B.Fab")
			(hide yes)
			(effects
				(font
					(size 1 1)
					(thickness 0.15)
				)
				(justify mirror)
			)
		)
		(property "Author" "Antmicro"
			(at 0 0 180)
			(unlocked yes)
			(layer "B.Fab")
			(hide yes)
			(effects
				(font
					(size 1 1)
					(thickness 0.15)
				)
				(justify mirror)
			)
		)
		(property "Tolerance" "~"
			(at 0 0 180)
			(unlocked yes)
			(layer "B.Fab")
			(hide yes)
			(effects
				(font
					(size 1 1)
					(thickness 0.15)
				)
				(justify mirror)
			)
		)
		(property "Current" "1A"
			(at 0 0 180)
			(unlocked yes)
			(layer "B.Fab")
			(hide yes)
			(effects
				(font
					(size 1 1)
					(thickness 0.15)
				)
				(justify mirror)
			)
		)
		(sheetname "/Recovery USB/")
		(sheetfile "recovery_usb.kicad_sch")
		(attr smd exclude_from_pos_files exclude_from_bom dnp)
		(fp_poly
			(pts
				(xy -0.925 0.47) (xy -0.925 -0.47) (xy 0.925 -0.47) (xy 0.925 0.47)
			)
			(stroke
				(width 0.05)
				(type default)
			)
			(fill no)
			(layer "B.CrtYd")
		)
		(fp_poly
			(pts
				(xy -0.5 0.25) (xy -0.5 -0.25) (xy 0.5 -0.25) (xy 0.5 0.25)
			)
			(stroke
				(width 0.15)
				(type solid)
			)
			(fill no)
			(layer "B.Fab")
		)
		(fp_text user "License: Apache-2.0"
			(at -0.949999 -5.169 0)
			(layer "B.Fab")
			(effects
				(font
					(size 0.7 0.7)
					(thickness 0.15)
				)
				(justify right top mirror)
			)
		)
		(fp_text user "${REFERENCE}"
			(at -0.95 -3.168 0)
			(layer "B.Fab")
			(effects
				(font
					(size 0.7 0.7)
					(thickness 0.15)
				)
				(justify right top mirror)
			)
		)
		(fp_text user "Author: Antmicro"
			(at -0.95 -4.169 0)
			(layer "B.Fab")
			(effects
				(font
					(size 0.7 0.7)
					(thickness 0.15)
				)
				(justify right top mirror)
			)
		)
		(pad "1" smd roundrect
			(at -0.48 0)
			(size 0.59 0.64)
			(layers "B.Cu" "B.Mask" "B.Paste")
			(roundrect_rratio 0.25)
			(net 850 "/I2C_{SYS}.SDA")
			(pintype "passive")
		)
		(pad "2" smd roundrect
			(at 0.48 0)
			(size 0.59 0.64)
			(layers "B.Cu" "B.Mask" "B.Paste")
			(roundrect_rratio 0.25)
			(net 1024 "/Recovery USB/USBC2_I2C_SDA")
			(pintype "passive")
		)
	)
)
